# BASEBOARD_FAB2 (Tioga Pass) — schematic netlist excerpt (pin names and nets, part order shuffled) for the footprints in the layout excerpt that follows; sources: Cadence DE-HDL packaged netlist, KiCad conversion of Wiwynn_Tioga_Pass_MB.brd

R1C11  RES  0.0 5% EMPTY  pkg 0402  page 182 : A = SMB_LAN_STBY_LVC3_SCL ; B = FAN_TACH1_R
R6B3  RES  221 1.0% CHIP  pkg 0402  page 21 : A = SVID_ALERT1_CPU0_N ; B = SVID_ALERT1_CPU0_R_N
R9E2  RES  10.0K 1% CHIP  pkg 0402  page 139 : A = P3V3_STBY ; B = PU_JTAG_SPRV_TCK

(kicad_pcb
	(version 20260206)
	(generator "pcbnew")
	(generator_version "10.0")
	(general
		(thickness 1.6)
		(legacy_teardrops no)
	)
	(paper "A4")
	(title_block
		(title "Wiwynn_Tioga_Pass_MB.brd")
		(comment 1 "Tioga Pass / footprints 438-440 of 4770")
	)
	(layers
		(0 "F.Cu" signal "TOP")
		(4 "In1.Cu" signal "L2GND")
		(6 "In2.Cu" signal "L3")
		(8 "In3.Cu" signal "L4GND")
		(10 "In4.Cu" signal "L5")
		(12 "In5.Cu" signal "L6GND")
		(14 "In6.Cu" signal "L7VCC")
		(16 "In7.Cu" signal "L8VCC")
		(18 "In8.Cu" signal "L9GND")
		(20 "In9.Cu" signal "L10")
		(22 "In10.Cu" signal "L11GND")
		(24 "In11.Cu" signal "L12")
		(26 "In12.Cu" signal "L13GND")
		(2 "B.Cu" signal "BOTTOM")
		(9 "F.Adhes" user "F.Adhesive")
		(11 "B.Adhes" user "B.Adhesive")
		(13 "F.Paste" user "Package Geometry/Pastemask Top")
		(15 "B.Paste" user "Package Geometry/Pastemask Bottom")
		(5 "F.SilkS" user "Ref Des/Silkscreen Top")
		(7 "B.SilkS" user "Ref Des/Silkscreen Bottom")
		(1 "F.Mask" user "Board Geometry/Soldermask Top")
		(3 "B.Mask" user "Board Geometry/Soldermask Bottom")
		(17 "Dwgs.User" user "User.Drawings")
		(19 "Cmts.User" user "User.Comments")
		(21 "Eco1.User" user "User.Eco1")
		(23 "Eco2.User" user "User.Eco2")
		(25 "Edge.Cuts" user "Board Geometry/Outline")
		(27 "Margin" user)
		(31 "F.CrtYd" user "Package Geometry/Place Bound Top")
		(29 "B.CrtYd" user "Package Geometry/Place Bound Bottom")
		(35 "F.Fab" user "Ref Des/Assembly Top")
		(33 "B.Fab" user "Ref Des/Assembly Bottom")
	)
	(footprint ""
		(layer "F.Cu")
		(at 487.6292 -50.6857)
		(property "Reference" "R9E2"
			(at 0 0 0)
			(layer "F.SilkS")
			(hide yes)
			(effects
				(font
					(size 1.27 1.27)
				)
			)
		)
		(property "Value" ""
			(at 0 0 0)
			(layer "F.Fab")
			(effects
				(font
					(size 1.27 1.27)
				)
			)
		)
		(duplicate_pad_numbers_are_jumpers no)
		(fp_poly
			(pts
				(xy -0.2794 -0.1016) (xy 0.2794 -0.1016) (xy 0.2794 0.9906) (xy -0.2794 0.9906)
			)
			(stroke
				(width 0)
				(type default)
			)
			(fill no)
			(layer "F.CrtYd")
		)
		(fp_line
			(start -0.2794 -0.1016)
			(end -0.2794 0.9906)
			(stroke
				(width 0.1)
				(type default)
			)
			(layer "F.Fab")
		)
		(fp_line
			(start -0.2794 0.9906)
			(end 0.2794 0.9906)
			(stroke
				(width 0.1)
				(type default)
			)
			(layer "F.Fab")
		)
		(fp_line
			(start 0.2794 -0.1016)
			(end -0.2794 -0.1016)
			(stroke
				(width 0.1)
				(type default)
			)
			(layer "F.Fab")
		)
		(fp_line
			(start 0.2794 0.9906)
			(end 0.2794 -0.1016)
			(stroke
				(width 0.1)
				(type default)
			)
			(layer "F.Fab")
		)
		(pad "1" smd rect
			(at 0 0)
			(size 0.508 0.508)
			(layers "F.Cu" "F.Mask" "F.Paste")
			(net "P3V3_STBY")
		)
		(pad "2" smd rect
			(at 0 0.889)
			(size 0.508 0.508)
			(layers "F.Cu" "F.Mask" "F.Paste")
			(net "PU_JTAG_SPRV_TCK")
		)
		(zone
			(layer "F.Cu")
			(hatch none 0.5)
			(connect_pads
				(clearance 0)
			)
			(min_thickness 0.25)
			(keepout
				(tracks allowed)
				(vias not_allowed)
				(pads allowed)
				(copperpour not_allowed)
				(footprints allowed)
			)
			(placement
				(enabled no)
				(sheetname "")
			)
			(fill
				(thermal_gap 0.5)
				(thermal_bridge_width 0.5)
				(island_removal_mode 0)
			)
			(polygon
				(pts
					(xy 487.3752 -50.4317) (xy 487.8832 -50.4317) (xy 487.8832 -50.0507) (xy 487.3752 -50.0507)
				)
			)
		)
		(zone
			(layer "F.Cu")
			(hatch none 0.5)
			(connect_pads
				(clearance 0)
			)
			(min_thickness 0.25)
			(keepout
				(tracks not_allowed)
				(vias allowed)
				(pads allowed)
				(copperpour not_allowed)
				(footprints allowed)
			)
			(placement
				(enabled no)
				(sheetname "")
			)
			(fill
				(thermal_gap 0.5)
				(thermal_bridge_width 0.5)
				(island_removal_mode 0)
			)
			(polygon
				(pts
					(xy 487.3752 -50.0507) (xy 487.8832 -50.0507) (xy 487.8832 -50.4317) (xy 487.3752 -50.4317)
				)
			)
		)
	)
	(footprint ""
		(layer "F.Cu")
		(at 15.113 -101.981)
		(property "Reference" "R1C11"
			(at 0 0 0)
			(layer "F.SilkS")
			(hide yes)
			(effects
				(font
					(size 1.27 1.27)
				)
			)
		)
		(property "Value" ""
			(at 0 0 0)
			(layer "F.Fab")
			(effects
				(font
					(size 1.27 1.27)
				)
			)
		)
		(duplicate_pad_numbers_are_jumpers no)
		(fp_poly
			(pts
				(xy -0.2794 -0.1016) (xy 0.2794 -0.1016) (xy 0.2794 0.9906) (xy -0.2794 0.9906)
			)
			(stroke
				(width 0)
				(type default)
			)
			(fill no)
			(layer "F.CrtYd")
		)
		(fp_line
			(start -0.2794 -0.1016)
			(end -0.2794 0.9906)
			(stroke
				(width 0.1)
				(type default)
			)
			(layer "F.Fab")
		)
		(fp_line
			(start -0.2794 0.9906)
			(end 0.2794 0.9906)
			(stroke
				(width 0.1)
				(type default)
			)
			(layer "F.Fab")
		)
		(fp_line
			(start 0.2794 -0.1016)
			(end -0.2794 -0.1016)
			(stroke
				(width 0.1)
				(type default)
			)
			(layer "F.Fab")
		)
		(fp_line
			(start 0.2794 0.9906)
			(end 0.2794 -0.1016)
			(stroke
				(width 0.1)
				(type default)
			)
			(layer "F.Fab")
		)
		(pad "1" smd rect
			(at 0 0)
			(size 0.508 0.508)
			(layers "F.Cu" "F.Mask" "F.Paste")
			(net "SMB_LAN_STBY_LVC3_SCL")
		)
		(pad "2" smd rect
			(at 0 0.889)
			(size 0.508 0.508)
			(layers "F.Cu" "F.Mask" "F.Paste")
			(net "FAN_TACH1_R")
		)
		(zone
			(layer "F.Cu")
			(hatch none 0.5)
			(connect_pads
				(clearance 0)
			)
			(min_thickness 0.25)
			(keepout
				(tracks allowed)
				(vias not_allowed)
				(pads allowed)
				(copperpour not_allowed)
				(footprints allowed)
			)
			(placement
				(enabled no)
				(sheetname "")
			)
			(fill
				(thermal_gap 0.5)
				(thermal_bridge_width 0.5)
				(island_removal_mode 0)
			)
			(polygon
				(pts
					(xy 14.859 -101.727) (xy 15.367 -101.727) (xy 15.367 -101.346) (xy 14.859 -101.346)
				)
			)
		)
		(zone
			(layer "F.Cu")
			(hatch none 0.5)
			(connect_pads
				(clearance 0)
			)
			(min_thickness 0.25)
			(keepout
				(tracks not_allowed)
				(vias allowed)
				(pads allowed)
				(copperpour not_allowed)
				(footprints allowed)
			)
			(placement
				(enabled no)
				(sheetname "")
			)
			(fill
				(thermal_gap 0.5)
				(thermal_bridge_width 0.5)
				(island_removal_mode 0)
			)
			(polygon
				(pts
					(xy 14.859 -101.346) (xy 15.367 -101.346) (xy 15.367 -101.727) (xy 14.859 -101.727)
				)
			)
		)
	)
	(footprint ""
		(layer "F.Cu")
		(at 322.27647 -128.38176 180)
		(property "Reference" "R6B3"
			(at 0 0 180)
			(layer "F.SilkS")
			(hide yes)
			(effects
				(font
					(size 1.27 1.27)
				)
			)
		)
		(property "Value" ""
			(at 0 0 180)
			(layer "F.Fab")
			(effects
				(font
					(size 1.27 1.27)
				)
			)
		)
		(duplicate_pad_numbers_are_jumpers no)
		(fp_poly
			(pts
				(xy -0.2794 -0.1016) (xy 0.2794 -0.1016) (xy 0.2794 0.9906) (xy -0.2794 0.9906)
			)
			(stroke
				(width 0)
				(type default)
			)
			(fill no)
			(layer "F.CrtYd")
		)
		(fp_line
			(start 0.2794 0.9906)
			(end 0.2794 -0.1016)
			(stroke
				(width 0.1)
				(type default)
			)
			(layer "F.Fab")
		)
		(fp_line
			(start 0.2794 -0.1016)
			(end -0.2794 -0.1016)
			(stroke
				(width 0.1)
				(type default)
			)
			(layer "F.Fab")
		)
		(fp_line
			(start -0.2794 0.9906)
			(end 0.2794 0.9906)
			(stroke
				(width 0.1)
				(type default)
			)
			(layer "F.Fab")
		)
		(fp_line
			(start -0.2794 -0.1016)
			(end -0.2794 0.9906)
			(stroke
				(width 0.1)
				(type default)
			)
			(layer "F.Fab")
		)
		(pad "1" smd rect
			(at 0 0 180)
			(size 0.508 0.508)
			(layers "F.Cu" "F.Mask" "F.Paste")
			(net "SVID_ALERT1_CPU0_N")
		)
		(pad "2" smd rect
			(at 0 0.889 180)
			(size 0.508 0.508)
			(layers "F.Cu" "F.Mask" "F.Paste")
			(net "SVID_ALERT1_CPU0_R_N")
		)
		(zone
			(layer "F.Cu")
			(hatch none 0.5)
			(connect_pads
				(clearance 0)
			)
			(min_thickness 0.25)
			(keepout
				(tracks not_allowed)
				(vias allowed)
				(pads allowed)
				(copperpour not_allowed)
				(footprints allowed)
			)
			(placement
				(enabled no)
				(sheetname "")
			)
			(fill
				(thermal_gap 0.5)
				(thermal_bridge_width 0.5)
				(island_removal_mode 0)
			)
			(polygon
				(pts
					(xy 322.53047 -129.01676) (xy 322.02247 -129.01676) (xy 322.02247 -128.63576) (xy 322.53047 -128.63576)
				)
			)
		)
		(zone
			(layer "F.Cu")
			(hatch none 0.5)
			(connect_pads
				(clearance 0)
			)
			(min_thickness 0.25)
			(keepout
				(tracks allowed)
				(vias not_allowed)
				(pads allowed)
				(copperpour not_allowed)
				(footprints allowed)
			)
			(placement
				(enabled no)
				(sheetname "")
			)
			(fill
				(thermal_gap 0.5)
				(thermal_bridge_width 0.5)
				(island_removal_mode 0)
			)
			(polygon
				(pts
					(xy 322.53047 -128.63576) (xy 322.02247 -128.63576) (xy 322.02247 -129.01676) (xy 322.53047 -129.01676)
				)
			)
		)
	)
)
